(kicad_pcb
	(version 20260206)
	(generator "pcbnew")
	(generator_version "10.0")
	(general
		(thickness 1.6)
		(legacy_teardrops no)
	)
	(paper "A4")
	(title_block
		(title "v1-chassis-manager — T6M_CM_d_v01_1031_1645.brd")
		(comment 1 "Open CloudServer (Microsoft) / footprints 2473-2482 of 2512")
	)
	(layers
		(0 "F.Cu" signal "TOP")
		(4 "In1.Cu" signal "GND1")
		(6 "In2.Cu" signal "IN1")
		(8 "In3.Cu" signal "VCC1")
		(10 "In4.Cu" signal "VCC2")
		(12 "In5.Cu" signal "GND2")
		(14 "In6.Cu" signal "IN2")
		(16 "In7.Cu" signal "IN3")
		(18 "In8.Cu" signal "GND3")
		(2 "B.Cu" signal "BOTTOM")
		(9 "F.Adhes" user "F.Adhesive")
		(11 "B.Adhes" user "B.Adhesive")
		(13 "F.Paste" user "Package Geometry/Pastemask Top")
		(15 "B.Paste" user "Package Geometry/Pastemask Bottom")
		(5 "F.SilkS" user "Ref Des/Silkscreen Top")
		(7 "B.SilkS" user "Ref Des/Silkscreen Bottom")
		(1 "F.Mask" user "Board Geometry/Soldermask Top")
		(3 "B.Mask" user "Board Geometry/Soldermask Bottom")
		(17 "Dwgs.User" user "User.Drawings")
		(19 "Cmts.User" user "User.Comments")
		(21 "Eco1.User" user "User.Eco1")
		(23 "Eco2.User" user "User.Eco2")
		(25 "Edge.Cuts" user "Board Geometry/Outline")
		(27 "Margin" user)
		(31 "F.CrtYd" user "Package Geometry/Place Bound Top")
		(29 "B.CrtYd" user "Package Geometry/Place Bound Bottom")
		(35 "F.Fab" user "Ref Des/Assembly Top")
		(33 "B.Fab" user "Ref Des/Assembly Bottom")
	)
	(footprint ""
		(layer "B.Cu")
		(at 108.56976 -185.205624 -90)
		(property "Reference" "C736"
			(at -3.957828 -0.41656 270)
			(unlocked yes)
			(layer "B.SilkS")
			(effects
				(font
					(size 0.7874 0.5842)
					(thickness 0.1524)
				)
				(justify left mirror)
			)
		)
		(property "Value" ""
			(at 0 0 90)
			(layer "B.Fab")
			(effects
				(font
					(size 1.27 1.27)
				)
				(justify mirror)
			)
		)
		(duplicate_pad_numbers_are_jumpers no)
		(fp_line
			(start -0.7874 0.4064)
			(end 0.7874 0.4064)
			(stroke
				(width 0.1524)
				(type default)
			)
			(layer "B.SilkS")
		)
		(fp_line
			(start 0.7874 0.4064)
			(end 0.7874 -0.4064)
			(stroke
				(width 0.1524)
				(type default)
			)
			(layer "B.SilkS")
		)
		(fp_line
			(start 0 0.381)
			(end 0 -0.381)
			(stroke
				(width 0.1524)
				(type default)
			)
			(layer "B.SilkS")
		)
		(fp_line
			(start -0.7874 -0.4064)
			(end -0.7874 0.4064)
			(stroke
				(width 0.1524)
				(type default)
			)
			(layer "B.SilkS")
		)
		(fp_line
			(start 0.7874 -0.4064)
			(end -0.7874 -0.4064)
			(stroke
				(width 0.1524)
				(type default)
			)
			(layer "B.SilkS")
		)
		(fp_poly
			(pts
				(xy 0.5334 0.254) (xy 0.635 0.254) (xy 0.635 0.2286) (xy 0.635 -0.254) (xy 0.5334 -0.254) (xy 0.5334 -0.2794)
				(xy -0.5334 -0.2794) (xy -0.5334 -0.254) (xy -0.635 -0.254) (xy -0.635 0.254) (xy -0.5334 0.254)
				(xy -0.5334 0.2794) (xy 0.508 0.2794) (xy 0.5334 0.2794)
			)
			(stroke
				(width 0)
				(type default)
			)
			(fill no)
			(layer "B.CrtYd")
		)
		(pad "1" smd rect
			(at -0.40005 0 90)
			(size 0.4572 0.508)
			(layers "B.Cu" "B.Mask" "B.Paste")
			(net "UART_T7_NODE4_RXD")
		)
		(pad "2" smd rect
			(at 0.40005 0 90)
			(size 0.4572 0.508)
			(layers "B.Cu" "B.Mask" "B.Paste")
			(net "GND")
		)
	)
	(footprint ""
		(layer "B.Cu")
		(at 125.80112 -150.935944 180)
		(property "Reference" "C200"
			(at 0.53086 -2.598166 0)
			(unlocked yes)
			(layer "B.SilkS")
			(effects
				(font
					(size 0.7874 0.5842)
					(thickness 0.1524)
				)
				(justify mirror)
			)
		)
		(property "Value" ""
			(at 0 0 0)
			(layer "B.Fab")
			(effects
				(font
					(size 1.27 1.27)
				)
				(justify mirror)
			)
		)
		(duplicate_pad_numbers_are_jumpers no)
		(fp_line
			(start 1.2954 0.5842)
			(end 1.2954 -0.5842)
			(stroke
				(width 0.1524)
				(type default)
			)
			(layer "B.SilkS")
		)
		(fp_line
			(start 1.2954 -0.5842)
			(end -1.2954 -0.5842)
			(stroke
				(width 0.1524)
				(type default)
			)
			(layer "B.SilkS")
		)
		(fp_line
			(start 0 -0.5842)
			(end 0 0.5842)
			(stroke
				(width 0.1524)
				(type default)
			)
			(layer "B.SilkS")
		)
		(fp_line
			(start -1.2954 0.5842)
			(end 1.2954 0.5842)
			(stroke
				(width 0.1524)
				(type default)
			)
			(layer "B.SilkS")
		)
		(fp_line
			(start -1.2954 -0.5842)
			(end -1.2954 0.5842)
			(stroke
				(width 0.1524)
				(type default)
			)
			(layer "B.SilkS")
		)
		(fp_poly
			(pts
				(xy -0.8636 -0.4572) (xy -0.8636 -0.3556) (xy -1.143 -0.3556) (xy -1.143 0.3556) (xy -0.8636 0.3556)
				(xy -0.8636 0.4572) (xy 0.8636 0.4572) (xy 0.8636 0.3556) (xy 1.143 0.3556) (xy 1.143 -0.3556) (xy 0.8636 -0.3556)
				(xy 0.8636 -0.4572)
			)
			(stroke
				(width 0)
				(type default)
			)
			(fill no)
			(layer "B.CrtYd")
		)
		(fp_line
			(start 0.884936 0.504952)
			(end 0.884936 -0.504952)
			(stroke
				(width 0.1)
				(type default)
			)
			(layer "B.Fab")
		)
		(fp_line
			(start 0.884936 -0.504952)
			(end -0.884936 -0.504952)
			(stroke
				(width 0.1)
				(type default)
			)
			(layer "B.Fab")
		)
		(fp_line
			(start -0.884936 0.504952)
			(end 0.884936 0.504952)
			(stroke
				(width 0.1)
				(type default)
			)
			(layer "B.Fab")
		)
		(fp_line
			(start -0.884936 -0.504952)
			(end -0.884936 0.504952)
			(stroke
				(width 0.1)
				(type default)
			)
			(layer "B.Fab")
		)
		(pad "1" smd rect
			(at -0.7366 0 270)
			(size 0.7112 0.8128)
			(layers "B.Cu" "B.Mask" "B.Paste")
			(net "P1V0_NODE1")
		)
		(pad "2" smd rect
			(at 0.7366 0 270)
			(size 0.7112 0.8128)
			(layers "B.Cu" "B.Mask" "B.Paste")
			(net "GND")
		)
	)
	(footprint ""
		(layer "B.Cu")
		(at 56.755538 -61.878718 180)
		(property "Reference" "C118"
			(at 14.695678 -30.534102 0)
			(unlocked yes)
			(layer "B.SilkS")
			(effects
				(font
					(size 0.7874 0.5842)
					(thickness 0.1524)
				)
				(justify left mirror)
			)
		)
		(property "Value" ""
			(at 0 0 0)
			(layer "B.Fab")
			(effects
				(font
					(size 1.27 1.27)
				)
				(justify mirror)
			)
		)
		(duplicate_pad_numbers_are_jumpers no)
		(fp_line
			(start 0.7874 0.4064)
			(end 0.7874 -0.4064)
			(stroke
				(width 0.1524)
				(type default)
			)
			(layer "B.SilkS")
		)
		(fp_line
			(start 0.7874 -0.4064)
			(end -0.7874 -0.4064)
			(stroke
				(width 0.1524)
				(type default)
			)
			(layer "B.SilkS")
		)
		(fp_line
			(start 0 0.381)
			(end 0 -0.381)
			(stroke
				(width 0.1524)
				(type default)
			)
			(layer "B.SilkS")
		)
		(fp_line
			(start -0.7874 0.4064)
			(end 0.7874 0.4064)
			(stroke
				(width 0.1524)
				(type default)
			)
			(layer "B.SilkS")
		)
		(fp_line
			(start -0.7874 -0.4064)
			(end -0.7874 0.4064)
			(stroke
				(width 0.1524)
				(type default)
			)
			(layer "B.SilkS")
		)
		(fp_poly
			(pts
				(xy 0.5334 0.254) (xy 0.635 0.254) (xy 0.635 0.2286) (xy 0.635 -0.254) (xy 0.5334 -0.254) (xy 0.5334 -0.2794)
				(xy -0.5334 -0.2794) (xy -0.5334 -0.254) (xy -0.635 -0.254) (xy -0.635 0.254) (xy -0.5334 0.254)
				(xy -0.5334 0.2794) (xy 0.508 0.2794) (xy 0.5334 0.2794)
			)
			(stroke
				(width 0)
				(type default)
			)
			(fill no)
			(layer "B.CrtYd")
		)
		(pad "1" smd rect
			(at -0.40005 0)
			(size 0.4572 0.508)
			(layers "B.Cu" "B.Mask" "B.Paste")
			(net "PV_VDDR_NODE1")
		)
		(pad "2" smd rect
			(at 0.40005 0)
			(size 0.4572 0.508)
			(layers "B.Cu" "B.Mask" "B.Paste")
			(net "GND")
		)
	)
	(footprint ""
		(layer "B.Cu")
		(at 156.83738 -148.727922)
		(property "Reference" "C444"
			(at 1.003554 3.515106 0)
			(unlocked yes)
			(layer "B.SilkS")
			(effects
				(font
					(size 0.7874 0.5842)
					(thickness 0.1524)
				)
				(justify left mirror)
			)
		)
		(property "Value" ""
			(at 0 0 0)
			(layer "B.Fab")
			(effects
				(font
					(size 1.27 1.27)
				)
				(justify mirror)
			)
		)
		(duplicate_pad_numbers_are_jumpers no)
		(fp_line
			(start -0.7874 -0.4064)
			(end -0.7874 0.4064)
			(stroke
				(width 0.1524)
				(type default)
			)
			(layer "B.SilkS")
		)
		(fp_line
			(start -0.7874 0.4064)
			(end 0.7874 0.4064)
			(stroke
				(width 0.1524)
				(type default)
			)
			(layer "B.SilkS")
		)
		(fp_line
			(start 0 0.381)
			(end 0 -0.381)
			(stroke
				(width 0.1524)
				(type default)
			)
			(layer "B.SilkS")
		)
		(fp_line
			(start 0.7874 -0.4064)
			(end -0.7874 -0.4064)
			(stroke
				(width 0.1524)
				(type default)
			)
			(layer "B.SilkS")
		)
		(fp_line
			(start 0.7874 0.4064)
			(end 0.7874 -0.4064)
			(stroke
				(width 0.1524)
				(type default)
			)
			(layer "B.SilkS")
		)
		(fp_poly
			(pts
				(xy 0.5334 0.254) (xy 0.635 0.254) (xy 0.635 0.2286) (xy 0.635 -0.254) (xy 0.5334 -0.254) (xy 0.5334 -0.2794)
				(xy -0.5334 -0.2794) (xy -0.5334 -0.254) (xy -0.635 -0.254) (xy -0.635 0.254) (xy -0.5334 0.254)
				(xy -0.5334 0.2794) (xy 0.508 0.2794) (xy 0.5334 0.2794)
			)
			(stroke
				(width 0)
				(type default)
			)
			(fill no)
			(layer "B.CrtYd")
		)
		(pad "1" smd rect
			(at -0.40005 0 180)
			(size 0.4572 0.508)
			(layers "B.Cu" "B.Mask" "B.Paste")
			(net "P3V3_NODE1")
		)
		(pad "2" smd rect
			(at 0.40005 0 180)
			(size 0.4572 0.508)
			(layers "B.Cu" "B.Mask" "B.Paste")
			(net "GND")
		)
	)
	(footprint ""
		(layer "B.Cu")
		(at 59.821572 -84.070698 90)
		(property "Reference" "R98"
			(at 0.918718 0.078994 270)
			(unlocked yes)
			(layer "B.SilkS")
			(effects
				(font
					(size 0.7874 0.5842)
					(thickness 0.1524)
				)
				(justify left mirror)
			)
		)
		(property "Value" ""
			(at 0 0 90)
			(layer "B.Fab")
			(effects
				(font
					(size 1.27 1.27)
				)
				(justify mirror)
			)
		)
		(duplicate_pad_numbers_are_jumpers no)
		(fp_line
			(start 0.7874 -0.4064)
			(end -0.7874 -0.4064)
			(stroke
				(width 0.1524)
				(type default)
			)
			(layer "B.SilkS")
		)
		(fp_line
			(start -0.7874 -0.4064)
			(end -0.7874 0.4064)
			(stroke
				(width 0.1524)
				(type default)
			)
			(layer "B.SilkS")
		)
		(fp_line
			(start 0.7874 0.4064)
			(end 0.7874 -0.4064)
			(stroke
				(width 0.1524)
				(type default)
			)
			(layer "B.SilkS")
		)
		(fp_line
			(start -0.7874 0.4064)
			(end 0.7874 0.4064)
			(stroke
				(width 0.1524)
				(type default)
			)
			(layer "B.SilkS")
		)
		(fp_poly
			(pts
				(xy 0.508 0.2794) (xy 0.508 0.2286) (xy 0.635 0.2286) (xy 0.635 -0.254) (xy 0.5334 -0.254) (xy 0.5334 -0.2794)
				(xy -0.5334 -0.2794) (xy -0.5334 -0.254) (xy -0.635 -0.254) (xy -0.635 0.254) (xy -0.5334 0.254)
				(xy -0.5334 0.2794)
			)
			(stroke
				(width 0)
				(type default)
			)
			(fill no)
			(layer "B.CrtYd")
		)
		(pad "1" smd rect
			(at -0.40005 0 270)
			(size 0.4572 0.508)
			(layers "B.Cu" "B.Mask" "B.Paste")
			(net "A_CPU_NODE1_HV_GPIO_RCOMP")
		)
		(pad "2" smd rect
			(at 0.40005 0 270)
			(size 0.4572 0.508)
			(layers "B.Cu" "B.Mask" "B.Paste")
			(net "GND")
		)
	)
	(footprint ""
		(layer "B.Cu")
		(at 69.262498 -96.696784 -90)
		(property "Reference" "R90"
			(at 3.227832 0.289052 270)
			(unlocked yes)
			(layer "B.SilkS")
			(effects
				(font
					(size 0.7874 0.5842)
					(thickness 0.1524)
				)
				(justify left mirror)
			)
		)
		(property "Value" ""
			(at 0 0 90)
			(layer "B.Fab")
			(effects
				(font
					(size 1.27 1.27)
				)
				(justify mirror)
			)
		)
		(duplicate_pad_numbers_are_jumpers no)
		(fp_line
			(start -0.7874 0.4064)
			(end 0.7874 0.4064)
			(stroke
				(width 0.1524)
				(type default)
			)
			(layer "B.SilkS")
		)
		(fp_line
			(start 0.7874 0.4064)
			(end 0.7874 -0.4064)
			(stroke
				(width 0.1524)
				(type default)
			)
			(layer "B.SilkS")
		)
		(fp_line
			(start -0.7874 -0.4064)
			(end -0.7874 0.4064)
			(stroke
				(width 0.1524)
				(type default)
			)
			(layer "B.SilkS")
		)
		(fp_line
			(start 0.7874 -0.4064)
			(end -0.7874 -0.4064)
			(stroke
				(width 0.1524)
				(type default)
			)
			(layer "B.SilkS")
		)
		(fp_poly
			(pts
				(xy 0.508 0.2794) (xy 0.508 0.2286) (xy 0.635 0.2286) (xy 0.635 -0.254) (xy 0.5334 -0.254) (xy 0.5334 -0.2794)
				(xy -0.5334 -0.2794) (xy -0.5334 -0.254) (xy -0.635 -0.254) (xy -0.635 0.254) (xy -0.5334 0.254)
				(xy -0.5334 0.2794)
			)
			(stroke
				(width 0)
				(type default)
			)
			(fill no)
			(layer "B.CrtYd")
		)
		(pad "1" smd rect
			(at -0.40005 0 90)
			(size 0.4572 0.508)
			(layers "B.Cu" "B.Mask" "B.Paste")
			(net "P3V3_NODE1")
		)
		(pad "2" smd rect
			(at 0.40005 0 90)
			(size 0.4572 0.508)
			(layers "B.Cu" "B.Mask" "B.Paste")
			(net "NODE1_BIOS_MB_REV_ID1")
		)
	)
	(footprint ""
		(layer "B.Cu")
		(at 105.191814 -110.95482)
		(property "Reference" "PC125"
			(at -3.119374 0.028956 0)
			(unlocked yes)
			(layer "B.SilkS")
			(effects
				(font
					(size 0.7874 0.5842)
					(thickness 0.1524)
				)
				(justify left mirror)
			)
		)
		(property "Value" ""
			(at 0 0 0)
			(layer "B.Fab")
			(effects
				(font
					(size 1.27 1.27)
				)
				(justify mirror)
			)
		)
		(duplicate_pad_numbers_are_jumpers no)
		(fp_line
			(start -1.905 -0.8636)
			(end -1.905 0.8636)
			(stroke
				(width 0.1524)
				(type default)
			)
			(layer "B.SilkS")
		)
		(fp_line
			(start -1.905 0.8636)
			(end 1.905 0.8636)
			(stroke
				(width 0.1524)
				(type default)
			)
			(layer "B.SilkS")
		)
		(fp_line
			(start 0 0.8382)
			(end 0 -0.8382)
			(stroke
				(width 0.1524)
				(type default)
			)
			(layer "B.SilkS")
		)
		(fp_line
			(start 1.905 -0.8636)
			(end -1.905 -0.8636)
			(stroke
				(width 0.1524)
				(type default)
			)
			(layer "B.SilkS")
		)
		(fp_line
			(start 1.905 0.8636)
			(end 1.905 -0.8636)
			(stroke
				(width 0.1524)
				(type default)
			)
			(layer "B.SilkS")
		)
		(fp_rect
			(start 1.524 0.7366)
			(end -1.524 -0.7366)
			(stroke
				(width 0)
				(type default)
			)
			(fill no)
			(layer "B.CrtYd")
		)
		(pad "1" smd rect
			(at -0.94996 0 180)
			(size 1.1176 1.3716)
			(layers "B.Cu" "B.Mask" "B.Paste")
			(net "GND")
		)
		(pad "2" smd rect
			(at 0.94996 0 180)
			(size 1.1176 1.3716)
			(layers "B.Cu" "B.Mask" "B.Paste")
			(net "PV_VCCP_NODE1")
		)
	)
	(footprint ""
		(layer "B.Cu")
		(at 70.867016 -124.98197 -90)
		(property "Reference" "C276"
			(at 2.34315 -8.641334 270)
			(unlocked yes)
			(layer "B.SilkS")
			(effects
				(font
					(size 0.7874 0.5842)
					(thickness 0.1524)
				)
				(justify mirror)
			)
		)
		(property "Value" ""
			(at 0 0 90)
			(layer "B.Fab")
			(effects
				(font
					(size 1.27 1.27)
				)
				(justify mirror)
			)
		)
		(duplicate_pad_numbers_are_jumpers no)
		(fp_line
			(start -1.2954 0.5842)
			(end 1.2954 0.5842)
			(stroke
				(width 0.1524)
				(type default)
			)
			(layer "B.SilkS")
		)
		(fp_line
			(start 1.2954 0.5842)
			(end 1.2954 -0.5842)
			(stroke
				(width 0.1524)
				(type default)
			)
			(layer "B.SilkS")
		)
		(fp_line
			(start -1.2954 -0.5842)
			(end -1.2954 0.5842)
			(stroke
				(width 0.1524)
				(type default)
			)
			(layer "B.SilkS")
		)
		(fp_line
			(start 0 -0.5842)
			(end 0 0.5842)
			(stroke
				(width 0.1524)
				(type default)
			)
			(layer "B.SilkS")
		)
		(fp_line
			(start 1.2954 -0.5842)
			(end -1.2954 -0.5842)
			(stroke
				(width 0.1524)
				(type default)
			)
			(layer "B.SilkS")
		)
		(fp_poly
			(pts
				(xy -0.8636 -0.4572) (xy -0.8636 -0.3556) (xy -1.143 -0.3556) (xy -1.143 0.3556) (xy -0.8636 0.3556)
				(xy -0.8636 0.4572) (xy 0.8636 0.4572) (xy 0.8636 0.3556) (xy 1.143 0.3556) (xy 1.143 -0.3556) (xy 0.8636 -0.3556)
				(xy 0.8636 -0.4572)
			)
			(stroke
				(width 0)
				(type default)
			)
			(fill no)
			(layer "B.CrtYd")
		)
		(fp_line
			(start -0.884936 0.504952)
			(end 0.884936 0.504952)
			(stroke
				(width 0.1)
				(type default)
			)
			(layer "B.Fab")
		)
		(fp_line
			(start 0.884936 0.504952)
			(end 0.884936 -0.504952)
			(stroke
				(width 0.1)
				(type default)
			)
			(layer "B.Fab")
		)
		(fp_line
			(start -0.884936 -0.504952)
			(end -0.884936 0.504952)
			(stroke
				(width 0.1)
				(type default)
			)
			(layer "B.Fab")
		)
		(fp_line
			(start 0.884936 -0.504952)
			(end -0.884936 -0.504952)
			(stroke
				(width 0.1)
				(type default)
			)
			(layer "B.Fab")
		)
		(pad "1" smd rect
			(at -0.7366 0)
			(size 0.7112 0.8128)
			(layers "B.Cu" "B.Mask" "B.Paste")
			(net "BMC_NODE1_VCC_1V8_PCIE")
		)
		(pad "2" smd rect
			(at 0.7366 0)
			(size 0.7112 0.8128)
			(layers "B.Cu" "B.Mask" "B.Paste")
			(net "GND")
		)
	)
	(footprint ""
		(layer "B.Cu")
		(at 65.706498 -99.181158 -90)
		(property "Reference" "R75"
			(at -1.095756 -0.127 270)
			(unlocked yes)
			(layer "B.SilkS")
			(effects
				(font
					(size 0.7874 0.5842)
					(thickness 0.1524)
				)
				(justify left mirror)
			)
		)
		(property "Value" ""
			(at 0 0 90)
			(layer "B.Fab")
			(effects
				(font
					(size 1.27 1.27)
				)
				(justify mirror)
			)
		)
		(duplicate_pad_numbers_are_jumpers no)
		(fp_line
			(start -0.7874 0.4064)
			(end 0.7874 0.4064)
			(stroke
				(width 0.1524)
				(type default)
			)
			(layer "B.SilkS")
		)
		(fp_line
			(start 0.7874 0.4064)
			(end 0.7874 -0.4064)
			(stroke
				(width 0.1524)
				(type default)
			)
			(layer "B.SilkS")
		)
		(fp_line
			(start -0.7874 -0.4064)
			(end -0.7874 0.4064)
			(stroke
				(width 0.1524)
				(type default)
			)
			(layer "B.SilkS")
		)
		(fp_line
			(start 0.7874 -0.4064)
			(end -0.7874 -0.4064)
			(stroke
				(width 0.1524)
				(type default)
			)
			(layer "B.SilkS")
		)
		(fp_poly
			(pts
				(xy 0.508 0.2794) (xy 0.508 0.2286) (xy 0.635 0.2286) (xy 0.635 -0.254) (xy 0.5334 -0.254) (xy 0.5334 -0.2794)
				(xy -0.5334 -0.2794) (xy -0.5334 -0.254) (xy -0.635 -0.254) (xy -0.635 0.254) (xy -0.5334 0.254)
				(xy -0.5334 0.2794)
			)
			(stroke
				(width 0)
				(type default)
			)
			(fill no)
			(layer "B.CrtYd")
		)
		(pad "1" smd rect
			(at -0.40005 0 90)
			(size 0.4572 0.508)
			(layers "B.Cu" "B.Mask" "B.Paste")
			(net "P3V3_SUS_NODE1")
		)
		(pad "2" smd rect
			(at 0.40005 0 90)
			(size 0.4572 0.508)
			(layers "B.Cu" "B.Mask" "B.Paste")
			(net "SPC_CPU_NODE1_RI_L")
		)
	)
	(footprint ""
		(layer "B.Cu")
		(at 62.506606 -121.057416 90)
		(property "Reference" "R316"
			(at -7.385304 10.219182 270)
			(unlocked yes)
			(layer "B.SilkS")
			(effects
				(font
					(size 0.7874 0.5842)
					(thickness 0.1524)
				)
				(justify left mirror)
			)
		)
		(property "Value" ""
			(at 0 0 90)
			(layer "B.Fab")
			(effects
				(font
					(size 1.27 1.27)
				)
				(justify mirror)
			)
		)
		(duplicate_pad_numbers_are_jumpers no)
		(fp_line
			(start 0.7874 -0.4064)
			(end -0.7874 -0.4064)
			(stroke
				(width 0.1524)
				(type default)
			)
			(layer "B.SilkS")
		)
		(fp_line
			(start -0.7874 -0.4064)
			(end -0.7874 0.4064)
			(stroke
				(width 0.1524)
				(type default)
			)
			(layer "B.SilkS")
		)
		(fp_line
			(start 0.7874 0.4064)
			(end 0.7874 -0.4064)
			(stroke
				(width 0.1524)
				(type default)
			)
			(layer "B.SilkS")
		)
		(fp_line
			(start -0.7874 0.4064)
			(end 0.7874 0.4064)
			(stroke
				(width 0.1524)
				(type default)
			)
			(layer "B.SilkS")
		)
		(fp_poly
			(pts
				(xy 0.508 0.2794) (xy 0.508 0.2286) (xy 0.635 0.2286) (xy 0.635 -0.254) (xy 0.5334 -0.254) (xy 0.5334 -0.2794)
				(xy -0.5334 -0.2794) (xy -0.5334 -0.254) (xy -0.635 -0.254) (xy -0.635 0.254) (xy -0.5334 0.254)
				(xy -0.5334 0.2794)
			)
			(stroke
				(width 0)
				(type default)
			)
			(fill no)
			(layer "B.CrtYd")
		)
		(pad "1" smd rect
			(at -0.40005 0 270)
			(size 0.4572 0.508)
			(layers "B.Cu" "B.Mask" "B.Paste")
			(net "P3V3_NODE1")
		)
		(pad "2" smd rect
			(at 0.40005 0 270)
			(size 0.4572 0.508)
			(layers "B.Cu" "B.Mask" "B.Paste")
			(net "BMC_ROMA0")
		)
	)
)
